# SCM (Grand Teton) — schematic netlist excerpt (pin names and nets, part order shuffled) for the footprints in the layout excerpt that follows; sources: Cadence DE-HDL packaged netlist, KiCad conversion of 12092022_DA0F0TMDCD0_F0T_Management_Board_D_brd_V3_OCP.brd

R817  Q_RES  100K 1% EMPTY  pkg 0402LF  page 12 : A = SMB_BMC_MM13_R_SCL ; B = GND
R521  Q_RES  10K 1% CHIP  pkg 0402LF  page 27 : A = P3V3_AUX ; B = SMB_BMC_MM10_SDA

(kicad_pcb
	(version 20260206)
	(generator "pcbnew")
	(generator_version "10.0")
	(general
		(thickness 1.6)
		(legacy_teardrops no)
	)
	(paper "A4")
	(title_block
		(title "12092022_DA0F0TMDCD0_F0T_Management_Board_D_brd_V3_OCP.brd")
		(comment 1 "Grand Teton / footprints 422-423 of 1440")
	)
	(layers
		(0 "F.Cu" signal "TOP")
		(4 "In1.Cu" signal "GND")
		(6 "In2.Cu" signal "IN1")
		(8 "In3.Cu" signal "GND1")
		(10 "In4.Cu" signal "IN2")
		(12 "In5.Cu" signal "VCC")
		(14 "In6.Cu" signal "VCC1")
		(16 "In7.Cu" signal "IN3")
		(18 "In8.Cu" signal "GND2")
		(20 "In9.Cu" signal "IN4")
		(22 "In10.Cu" signal "GND3")
		(2 "B.Cu" signal "BOTTOM")
		(9 "F.Adhes" user "F.Adhesive")
		(11 "B.Adhes" user "B.Adhesive")
		(13 "F.Paste" user "Package Geometry/Pastemask Top")
		(15 "B.Paste" user "Package Geometry/Pastemask Bottom")
		(5 "F.SilkS" user "Ref Des/Silkscreen Top")
		(7 "B.SilkS" user "Ref Des/Silkscreen Bottom")
		(1 "F.Mask" user "Board Geometry/Soldermask Top")
		(3 "B.Mask" user "Board Geometry/Soldermask Bottom")
		(17 "Dwgs.User" user "User.Drawings")
		(19 "Cmts.User" user "User.Comments")
		(21 "Eco1.User" user "User.Eco1")
		(23 "Eco2.User" user "User.Eco2")
		(25 "Edge.Cuts" user "Board Geometry/Outline")
		(27 "Margin" user)
		(31 "F.CrtYd" user "Package Geometry/Place Bound Top")
		(29 "B.CrtYd" user "Package Geometry/Place Bound Bottom")
		(35 "F.Fab" user "Ref Des/Assembly Top")
		(33 "B.Fab" user "Ref Des/Assembly Bottom")
	)
	(footprint ""
		(layer "F.Cu")
		(at 54.473856 -30.867604 90)
		(property "Reference" "R521"
			(at 0 0 90)
			(layer "F.SilkS")
			(hide yes)
			(effects
				(font
					(size 1.27 1.27)
				)
			)
		)
		(property "Value" ""
			(at 0 0 90)
			(layer "F.Fab")
			(effects
				(font
					(size 1.27 1.27)
				)
			)
		)
		(duplicate_pad_numbers_are_jumpers no)
		(fp_line
			(start 0.7874 -0.4064)
			(end 0.7874 0.4064)
			(stroke
				(width 0.1524)
				(type default)
			)
			(layer "F.SilkS")
		)
		(fp_line
			(start -0.7874 -0.4064)
			(end 0.7874 -0.4064)
			(stroke
				(width 0.1524)
				(type default)
			)
			(layer "F.SilkS")
		)
		(fp_line
			(start 0.7874 0.4064)
			(end -0.7874 0.4064)
			(stroke
				(width 0.1524)
				(type default)
			)
			(layer "F.SilkS")
		)
		(fp_line
			(start -0.7874 0.4064)
			(end -0.7874 -0.4064)
			(stroke
				(width 0.1524)
				(type default)
			)
			(layer "F.SilkS")
		)
		(fp_line
			(start -0.12065 -0.305054)
			(end -0.12065 -0.2794)
			(stroke
				(width 0.1)
				(type default)
			)
			(layer "F.Fab")
		)
		(fp_line
			(start -0.67945 -0.305054)
			(end -0.12065 -0.305054)
			(stroke
				(width 0.1)
				(type default)
			)
			(layer "F.Fab")
		)
		(fp_line
			(start 0.67945 -0.3048)
			(end 0.67945 0.3048)
			(stroke
				(width 0.1)
				(type default)
			)
			(layer "F.Fab")
		)
		(fp_line
			(start 0.12065 -0.3048)
			(end 0.67945 -0.3048)
			(stroke
				(width 0.1)
				(type default)
			)
			(layer "F.Fab")
		)
		(fp_line
			(start 0.12065 -0.2794)
			(end 0.12065 -0.3048)
			(stroke
				(width 0.1)
				(type default)
			)
			(layer "F.Fab")
		)
		(fp_line
			(start -0.12065 -0.2794)
			(end 0.12065 -0.2794)
			(stroke
				(width 0.1)
				(type default)
			)
			(layer "F.Fab")
		)
		(fp_line
			(start 0.120396 0.2794)
			(end -0.12065 0.2794)
			(stroke
				(width 0.1)
				(type default)
			)
			(layer "F.Fab")
		)
		(fp_line
			(start -0.12065 0.2794)
			(end -0.12065 0.3048)
			(stroke
				(width 0.1)
				(type default)
			)
			(layer "F.Fab")
		)
		(fp_line
			(start 0.67945 0.3048)
			(end 0.120396 0.3048)
			(stroke
				(width 0.1)
				(type default)
			)
			(layer "F.Fab")
		)
		(fp_line
			(start 0.120396 0.3048)
			(end 0.120396 0.2794)
			(stroke
				(width 0.1)
				(type default)
			)
			(layer "F.Fab")
		)
		(fp_line
			(start -0.12065 0.3048)
			(end -0.67945 0.3048)
			(stroke
				(width 0.1)
				(type default)
			)
			(layer "F.Fab")
		)
		(fp_line
			(start -0.67945 0.3048)
			(end -0.67945 -0.305054)
			(stroke
				(width 0.1)
				(type default)
			)
			(layer "F.Fab")
		)
		(pad "1" smd circle
			(at -0.40005 0 90)
			(size 0 0)
			(layers "F.Cu" "F.Mask" "F.Paste")
			(net "P3V3_AUX")
		)
		(pad "2" smd circle
			(at 0.40005 0 90)
			(size 0 0)
			(layers "F.Cu" "F.Mask" "F.Paste")
			(net "SMB_BMC_MM10_SDA")
		)
	)
	(footprint ""
		(layer "F.Cu")
		(at 39.905686 -46.391576 180)
		(property "Reference" "R817"
			(at 0 0 180)
			(layer "F.SilkS")
			(hide yes)
			(effects
				(font
					(size 1.27 1.27)
				)
			)
		)
		(property "Value" ""
			(at 0 0 180)
			(layer "F.Fab")
			(effects
				(font
					(size 1.27 1.27)
				)
			)
		)
		(duplicate_pad_numbers_are_jumpers no)
		(fp_line
			(start 0.7874 0.4064)
			(end -0.7874 0.4064)
			(stroke
				(width 0.1524)
				(type default)
			)
			(layer "F.SilkS")
		)
		(fp_line
			(start 0.7874 -0.4064)
			(end 0.7874 0.4064)
			(stroke
				(width 0.1524)
				(type default)
			)
			(layer "F.SilkS")
		)
		(fp_line
			(start -0.7874 0.4064)
			(end -0.7874 -0.4064)
			(stroke
				(width 0.1524)
				(type default)
			)
			(layer "F.SilkS")
		)
		(fp_line
			(start -0.7874 -0.4064)
			(end 0.7874 -0.4064)
			(stroke
				(width 0.1524)
				(type default)
			)
			(layer "F.SilkS")
		)
		(fp_line
			(start 0.67945 0.3048)
			(end 0.120396 0.3048)
			(stroke
				(width 0.1)
				(type default)
			)
			(layer "F.Fab")
		)
		(fp_line
			(start 0.67945 -0.3048)
			(end 0.67945 0.3048)
			(stroke
				(width 0.1)
				(type default)
			)
			(layer "F.Fab")
		)
		(fp_line
			(start 0.12065 -0.2794)
			(end 0.12065 -0.3048)
			(stroke
				(width 0.1)
				(type default)
			)
			(layer "F.Fab")
		)
		(fp_line
			(start 0.12065 -0.3048)
			(end 0.67945 -0.3048)
			(stroke
				(width 0.1)
				(type default)
			)
			(layer "F.Fab")
		)
		(fp_line
			(start 0.120396 0.3048)
			(end 0.120396 0.2794)
			(stroke
				(width 0.1)
				(type default)
			)
			(layer "F.Fab")
		)
		(fp_line
			(start 0.120396 0.2794)
			(end -0.12065 0.2794)
			(stroke
				(width 0.1)
				(type default)
			)
			(layer "F.Fab")
		)
		(fp_line
			(start -0.12065 0.3048)
			(end -0.67945 0.3048)
			(stroke
				(width 0.1)
				(type default)
			)
			(layer "F.Fab")
		)
		(fp_line
			(start -0.12065 0.2794)
			(end -0.12065 0.3048)
			(stroke
				(width 0.1)
				(type default)
			)
			(layer "F.Fab")
		)
		(fp_line
			(start -0.12065 -0.2794)
			(end 0.12065 -0.2794)
			(stroke
				(width 0.1)
				(type default)
			)
			(layer "F.Fab")
		)
		(fp_line
			(start -0.12065 -0.305054)
			(end -0.12065 -0.2794)
			(stroke
				(width 0.1)
				(type default)
			)
			(layer "F.Fab")
		)
		(fp_line
			(start -0.67945 0.3048)
			(end -0.67945 -0.305054)
			(stroke
				(width 0.1)
				(type default)
			)
			(layer "F.Fab")
		)
		(fp_line
			(start -0.67945 -0.305054)
			(end -0.12065 -0.305054)
			(stroke
				(width 0.1)
				(type default)
			)
			(layer "F.Fab")
		)
		(pad "1" smd circle
			(at -0.40005 0 180)
			(size 0 0)
			(layers "F.Cu" "F.Mask" "F.Paste")
			(net "SMB_BMC_MM13_R_SCL")
		)
		(pad "2" smd circle
			(at 0.40005 0 180)
			(size 0 0)
			(layers "F.Cu" "F.Mask" "F.Paste")
			(net "GND")
		)
	)
)
